FILE_TYPE = CONNECTIVITY;
{Allegro Design Entry HDL 17.2-2016 S066 (3851973) 4/6/2020}
"PAGE_NUMBER" = 521;
0"NC";
END.
